(kicad_pcb
	(version 20260206)
	(generator "pcbnew")
	(generator_version "10.0")
	(general
		(thickness 1.6)
		(legacy_teardrops no)
	)
	(paper "A4")
	(title_block
		(title "9052_F0T_PDB_Converter_Brick_F_V03_1208_1600_OCP.brd")
		(comment 1 "Grand Teton / footprints 369-374 of 578")
	)
	(layers
		(0 "F.Cu" signal "TOP")
		(4 "In1.Cu" signal "GND")
		(6 "In2.Cu" signal "IN1")
		(8 "In3.Cu" signal "GND1")
		(10 "In4.Cu" signal "VCC")
		(12 "In5.Cu" signal "VCC1")
		(14 "In6.Cu" signal "GND2")
		(16 "In7.Cu" signal "IN2")
		(18 "In8.Cu" signal "GND3")
		(2 "B.Cu" signal "BOTTOM")
		(9 "F.Adhes" user "F.Adhesive")
		(11 "B.Adhes" user "B.Adhesive")
		(13 "F.Paste" user "Package Geometry/Pastemask Top")
		(15 "B.Paste" user "Package Geometry/Pastemask Bottom")
		(5 "F.SilkS" user "Ref Des/Silkscreen Top")
		(7 "B.SilkS" user "Ref Des/Silkscreen Bottom")
		(1 "F.Mask" user "Board Geometry/Soldermask Top")
		(3 "B.Mask" user "Board Geometry/Soldermask Bottom")
		(17 "Dwgs.User" user "User.Drawings")
		(19 "Cmts.User" user "User.Comments")
		(21 "Eco1.User" user "User.Eco1")
		(23 "Eco2.User" user "User.Eco2")
		(25 "Edge.Cuts" user "Board Geometry/Outline")
		(27 "Margin" user)
		(31 "F.CrtYd" user "Package Geometry/Place Bound Top")
		(29 "B.CrtYd" user "Package Geometry/Place Bound Bottom")
		(35 "F.Fab" user "Ref Des/Assembly Top")
		(33 "B.Fab" user "Ref Des/Assembly Bottom")
	)
	(footprint ""
		(layer "B.Cu")
		(at 212.344 -83.312)
		(property "Reference" "R28"
			(at 0 0 0)
			(layer "B.SilkS")
			(hide yes)
			(effects
				(font
					(size 1.27 1.27)
				)
				(justify mirror)
			)
		)
		(property "Value" ""
			(at 0 0 0)
			(layer "B.Fab")
			(effects
				(font
					(size 1.27 1.27)
				)
				(justify mirror)
			)
		)
		(duplicate_pad_numbers_are_jumpers no)
		(fp_line
			(start -0.7874 -0.4064)
			(end -0.7874 0.4064)
			(stroke
				(width 0.1524)
				(type default)
			)
			(layer "B.SilkS")
		)
		(fp_line
			(start -0.7874 0.4064)
			(end 0.7874 0.4064)
			(stroke
				(width 0.1524)
				(type default)
			)
			(layer "B.SilkS")
		)
		(fp_line
			(start 0.7874 -0.4064)
			(end -0.7874 -0.4064)
			(stroke
				(width 0.1524)
				(type default)
			)
			(layer "B.SilkS")
		)
		(fp_line
			(start 0.7874 0.4064)
			(end 0.7874 -0.4064)
			(stroke
				(width 0.1524)
				(type default)
			)
			(layer "B.SilkS")
		)
		(fp_line
			(start -0.67945 -0.3048)
			(end -0.67945 0.3048)
			(stroke
				(width 0.1)
				(type default)
			)
			(layer "B.Fab")
		)
		(fp_line
			(start -0.67945 0.3048)
			(end -0.120396 0.3048)
			(stroke
				(width 0.1)
				(type default)
			)
			(layer "B.Fab")
		)
		(fp_line
			(start -0.12065 -0.3048)
			(end -0.67945 -0.3048)
			(stroke
				(width 0.1)
				(type default)
			)
			(layer "B.Fab")
		)
		(fp_line
			(start -0.12065 -0.2794)
			(end -0.12065 -0.3048)
			(stroke
				(width 0.1)
				(type default)
			)
			(layer "B.Fab")
		)
		(fp_line
			(start -0.120396 0.2794)
			(end 0.12065 0.2794)
			(stroke
				(width 0.1)
				(type default)
			)
			(layer "B.Fab")
		)
		(fp_line
			(start -0.120396 0.3048)
			(end -0.120396 0.2794)
			(stroke
				(width 0.1)
				(type default)
			)
			(layer "B.Fab")
		)
		(fp_line
			(start 0.12065 -0.305054)
			(end 0.12065 -0.2794)
			(stroke
				(width 0.1)
				(type default)
			)
			(layer "B.Fab")
		)
		(fp_line
			(start 0.12065 -0.2794)
			(end -0.12065 -0.2794)
			(stroke
				(width 0.1)
				(type default)
			)
			(layer "B.Fab")
		)
		(fp_line
			(start 0.12065 0.2794)
			(end 0.12065 0.3048)
			(stroke
				(width 0.1)
				(type default)
			)
			(layer "B.Fab")
		)
		(fp_line
			(start 0.12065 0.3048)
			(end 0.67945 0.3048)
			(stroke
				(width 0.1)
				(type default)
			)
			(layer "B.Fab")
		)
		(fp_line
			(start 0.67945 -0.305054)
			(end 0.12065 -0.305054)
			(stroke
				(width 0.1)
				(type default)
			)
			(layer "B.Fab")
		)
		(fp_line
			(start 0.67945 0.3048)
			(end 0.67945 -0.305054)
			(stroke
				(width 0.1)
				(type default)
			)
			(layer "B.Fab")
		)
		(pad "1" smd circle
			(at 0.40005 0 180)
			(size 0 0)
			(layers "B.Cu" "B.Mask" "B.Paste")
			(net "P3V3_AUX")
		)
		(pad "2" smd circle
			(at -0.40005 0 180)
			(size 0 0)
			(layers "B.Cu" "B.Mask" "B.Paste")
			(net "PWRGD_GPU_HSC")
		)
	)
	(footprint ""
		(layer "B.Cu")
		(at 266.192 -33.9344)
		(property "Reference" "PR214"
			(at 0 0 0)
			(layer "B.SilkS")
			(hide yes)
			(effects
				(font
					(size 1.27 1.27)
				)
				(justify mirror)
			)
		)
		(property "Value" ""
			(at 0 0 0)
			(layer "B.Fab")
			(effects
				(font
					(size 1.27 1.27)
				)
				(justify mirror)
			)
		)
		(duplicate_pad_numbers_are_jumpers no)
		(fp_line
			(start -0.7874 -0.4064)
			(end -0.7874 0.4064)
			(stroke
				(width 0.1524)
				(type default)
			)
			(layer "B.SilkS")
		)
		(fp_line
			(start -0.7874 0.4064)
			(end 0.7874 0.4064)
			(stroke
				(width 0.1524)
				(type default)
			)
			(layer "B.SilkS")
		)
		(fp_line
			(start 0.7874 -0.4064)
			(end -0.7874 -0.4064)
			(stroke
				(width 0.1524)
				(type default)
			)
			(layer "B.SilkS")
		)
		(fp_line
			(start 0.7874 0.4064)
			(end 0.7874 -0.4064)
			(stroke
				(width 0.1524)
				(type default)
			)
			(layer "B.SilkS")
		)
		(fp_line
			(start -0.67945 -0.3048)
			(end -0.67945 0.3048)
			(stroke
				(width 0.1)
				(type default)
			)
			(layer "B.Fab")
		)
		(fp_line
			(start -0.67945 0.3048)
			(end -0.120396 0.3048)
			(stroke
				(width 0.1)
				(type default)
			)
			(layer "B.Fab")
		)
		(fp_line
			(start -0.12065 -0.3048)
			(end -0.67945 -0.3048)
			(stroke
				(width 0.1)
				(type default)
			)
			(layer "B.Fab")
		)
		(fp_line
			(start -0.12065 -0.2794)
			(end -0.12065 -0.3048)
			(stroke
				(width 0.1)
				(type default)
			)
			(layer "B.Fab")
		)
		(fp_line
			(start -0.120396 0.2794)
			(end 0.12065 0.2794)
			(stroke
				(width 0.1)
				(type default)
			)
			(layer "B.Fab")
		)
		(fp_line
			(start -0.120396 0.3048)
			(end -0.120396 0.2794)
			(stroke
				(width 0.1)
				(type default)
			)
			(layer "B.Fab")
		)
		(fp_line
			(start 0.12065 -0.305054)
			(end 0.12065 -0.2794)
			(stroke
				(width 0.1)
				(type default)
			)
			(layer "B.Fab")
		)
		(fp_line
			(start 0.12065 -0.2794)
			(end -0.12065 -0.2794)
			(stroke
				(width 0.1)
				(type default)
			)
			(layer "B.Fab")
		)
		(fp_line
			(start 0.12065 0.2794)
			(end 0.12065 0.3048)
			(stroke
				(width 0.1)
				(type default)
			)
			(layer "B.Fab")
		)
		(fp_line
			(start 0.12065 0.3048)
			(end 0.67945 0.3048)
			(stroke
				(width 0.1)
				(type default)
			)
			(layer "B.Fab")
		)
		(fp_line
			(start 0.67945 -0.305054)
			(end 0.12065 -0.305054)
			(stroke
				(width 0.1)
				(type default)
			)
			(layer "B.Fab")
		)
		(fp_line
			(start 0.67945 0.3048)
			(end 0.67945 -0.305054)
			(stroke
				(width 0.1)
				(type default)
			)
			(layer "B.Fab")
		)
		(pad "1" smd circle
			(at 0.40005 0 180)
			(size 0 0)
			(layers "B.Cu" "B.Mask" "B.Paste")
			(net "P52V_HS1_MODE")
		)
		(pad "2" smd circle
			(at -0.40005 0 180)
			(size 0 0)
			(layers "B.Cu" "B.Mask" "B.Paste")
			(net "P52V_HS1_INTVCC")
		)
	)
	(footprint ""
		(layer "B.Cu")
		(at 94.361 -78.613)
		(property "Reference" "R175"
			(at 0 0 0)
			(layer "B.SilkS")
			(hide yes)
			(effects
				(font
					(size 1.27 1.27)
				)
				(justify mirror)
			)
		)
		(property "Value" ""
			(at 0 0 0)
			(layer "B.Fab")
			(effects
				(font
					(size 1.27 1.27)
				)
				(justify mirror)
			)
		)
		(duplicate_pad_numbers_are_jumpers no)
		(fp_line
			(start -0.7874 -0.4064)
			(end -0.7874 0.4064)
			(stroke
				(width 0.1524)
				(type default)
			)
			(layer "B.SilkS")
		)
		(fp_line
			(start -0.7874 0.4064)
			(end 0.7874 0.4064)
			(stroke
				(width 0.1524)
				(type default)
			)
			(layer "B.SilkS")
		)
		(fp_line
			(start 0.7874 -0.4064)
			(end -0.7874 -0.4064)
			(stroke
				(width 0.1524)
				(type default)
			)
			(layer "B.SilkS")
		)
		(fp_line
			(start 0.7874 0.4064)
			(end 0.7874 -0.4064)
			(stroke
				(width 0.1524)
				(type default)
			)
			(layer "B.SilkS")
		)
		(fp_line
			(start -0.67945 -0.3048)
			(end -0.67945 0.3048)
			(stroke
				(width 0.1)
				(type default)
			)
			(layer "B.Fab")
		)
		(fp_line
			(start -0.67945 0.3048)
			(end -0.120396 0.3048)
			(stroke
				(width 0.1)
				(type default)
			)
			(layer "B.Fab")
		)
		(fp_line
			(start -0.12065 -0.3048)
			(end -0.67945 -0.3048)
			(stroke
				(width 0.1)
				(type default)
			)
			(layer "B.Fab")
		)
		(fp_line
			(start -0.12065 -0.2794)
			(end -0.12065 -0.3048)
			(stroke
				(width 0.1)
				(type default)
			)
			(layer "B.Fab")
		)
		(fp_line
			(start -0.120396 0.2794)
			(end 0.12065 0.2794)
			(stroke
				(width 0.1)
				(type default)
			)
			(layer "B.Fab")
		)
		(fp_line
			(start -0.120396 0.3048)
			(end -0.120396 0.2794)
			(stroke
				(width 0.1)
				(type default)
			)
			(layer "B.Fab")
		)
		(fp_line
			(start 0.12065 -0.305054)
			(end 0.12065 -0.2794)
			(stroke
				(width 0.1)
				(type default)
			)
			(layer "B.Fab")
		)
		(fp_line
			(start 0.12065 -0.2794)
			(end -0.12065 -0.2794)
			(stroke
				(width 0.1)
				(type default)
			)
			(layer "B.Fab")
		)
		(fp_line
			(start 0.12065 0.2794)
			(end 0.12065 0.3048)
			(stroke
				(width 0.1)
				(type default)
			)
			(layer "B.Fab")
		)
		(fp_line
			(start 0.12065 0.3048)
			(end 0.67945 0.3048)
			(stroke
				(width 0.1)
				(type default)
			)
			(layer "B.Fab")
		)
		(fp_line
			(start 0.67945 -0.305054)
			(end 0.12065 -0.305054)
			(stroke
				(width 0.1)
				(type default)
			)
			(layer "B.Fab")
		)
		(fp_line
			(start 0.67945 0.3048)
			(end 0.67945 -0.305054)
			(stroke
				(width 0.1)
				(type default)
			)
			(layer "B.Fab")
		)
		(pad "1" smd circle
			(at 0.40005 0 180)
			(size 0 0)
			(layers "B.Cu" "B.Mask" "B.Paste")
			(net "P3V3_AUX")
		)
		(pad "2" smd circle
			(at -0.40005 0 180)
			(size 0 0)
			(layers "B.Cu" "B.Mask" "B.Paste")
			(net "P12V_BRICK1_ALERT_N")
		)
	)
	(footprint ""
		(layer "B.Cu")
		(at 139.065 -76.327 180)
		(property "Reference" "R166"
			(at 0 0 0)
			(layer "B.SilkS")
			(hide yes)
			(effects
				(font
					(size 1.27 1.27)
				)
				(justify mirror)
			)
		)
		(property "Value" ""
			(at 0 0 0)
			(layer "B.Fab")
			(effects
				(font
					(size 1.27 1.27)
				)
				(justify mirror)
			)
		)
		(duplicate_pad_numbers_are_jumpers no)
		(fp_line
			(start 0.7874 0.4064)
			(end 0.7874 -0.4064)
			(stroke
				(width 0.1524)
				(type default)
			)
			(layer "B.SilkS")
		)
		(fp_line
			(start 0.7874 -0.4064)
			(end -0.7874 -0.4064)
			(stroke
				(width 0.1524)
				(type default)
			)
			(layer "B.SilkS")
		)
		(fp_line
			(start -0.7874 0.4064)
			(end 0.7874 0.4064)
			(stroke
				(width 0.1524)
				(type default)
			)
			(layer "B.SilkS")
		)
		(fp_line
			(start -0.7874 -0.4064)
			(end -0.7874 0.4064)
			(stroke
				(width 0.1524)
				(type default)
			)
			(layer "B.SilkS")
		)
		(fp_line
			(start 0.67945 0.3048)
			(end 0.67945 -0.305054)
			(stroke
				(width 0.1)
				(type default)
			)
			(layer "B.Fab")
		)
		(fp_line
			(start 0.67945 -0.305054)
			(end 0.12065 -0.305054)
			(stroke
				(width 0.1)
				(type default)
			)
			(layer "B.Fab")
		)
		(fp_line
			(start 0.12065 0.3048)
			(end 0.67945 0.3048)
			(stroke
				(width 0.1)
				(type default)
			)
			(layer "B.Fab")
		)
		(fp_line
			(start 0.12065 0.2794)
			(end 0.12065 0.3048)
			(stroke
				(width 0.1)
				(type default)
			)
			(layer "B.Fab")
		)
		(fp_line
			(start 0.12065 -0.2794)
			(end -0.12065 -0.2794)
			(stroke
				(width 0.1)
				(type default)
			)
			(layer "B.Fab")
		)
		(fp_line
			(start 0.12065 -0.305054)
			(end 0.12065 -0.2794)
			(stroke
				(width 0.1)
				(type default)
			)
			(layer "B.Fab")
		)
		(fp_line
			(start -0.120396 0.3048)
			(end -0.120396 0.2794)
			(stroke
				(width 0.1)
				(type default)
			)
			(layer "B.Fab")
		)
		(fp_line
			(start -0.120396 0.2794)
			(end 0.12065 0.2794)
			(stroke
				(width 0.1)
				(type default)
			)
			(layer "B.Fab")
		)
		(fp_line
			(start -0.12065 -0.2794)
			(end -0.12065 -0.3048)
			(stroke
				(width 0.1)
				(type default)
			)
			(layer "B.Fab")
		)
		(fp_line
			(start -0.12065 -0.3048)
			(end -0.67945 -0.3048)
			(stroke
				(width 0.1)
				(type default)
			)
			(layer "B.Fab")
		)
		(fp_line
			(start -0.67945 0.3048)
			(end -0.120396 0.3048)
			(stroke
				(width 0.1)
				(type default)
			)
			(layer "B.Fab")
		)
		(fp_line
			(start -0.67945 -0.3048)
			(end -0.67945 0.3048)
			(stroke
				(width 0.1)
				(type default)
			)
			(layer "B.Fab")
		)
		(pad "1" smd circle
			(at 0.40005 0)
			(size 0 0)
			(layers "B.Cu" "B.Mask" "B.Paste")
			(net "SMB_P52V_VPDB_SCL")
		)
		(pad "2" smd circle
			(at -0.40005 0)
			(size 0 0)
			(layers "B.Cu" "B.Mask" "B.Paste")
			(net "SMB_BRICK0_SCL")
		)
	)
	(footprint ""
		(layer "B.Cu")
		(at 238.555784 -78.96479 180)
		(property "Reference" "R2"
			(at 0 0 0)
			(layer "B.SilkS")
			(hide yes)
			(effects
				(font
					(size 1.27 1.27)
				)
				(justify mirror)
			)
		)
		(property "Value" ""
			(at 0 0 0)
			(layer "B.Fab")
			(effects
				(font
					(size 1.27 1.27)
				)
				(justify mirror)
			)
		)
		(duplicate_pad_numbers_are_jumpers no)
		(fp_line
			(start 0.7874 0.4064)
			(end 0.7874 -0.4064)
			(stroke
				(width 0.1524)
				(type default)
			)
			(layer "B.SilkS")
		)
		(fp_line
			(start 0.7874 -0.4064)
			(end -0.7874 -0.4064)
			(stroke
				(width 0.1524)
				(type default)
			)
			(layer "B.SilkS")
		)
		(fp_line
			(start -0.7874 0.4064)
			(end 0.7874 0.4064)
			(stroke
				(width 0.1524)
				(type default)
			)
			(layer "B.SilkS")
		)
		(fp_line
			(start -0.7874 -0.4064)
			(end -0.7874 0.4064)
			(stroke
				(width 0.1524)
				(type default)
			)
			(layer "B.SilkS")
		)
		(fp_line
			(start 0.67945 0.3048)
			(end 0.67945 -0.305054)
			(stroke
				(width 0.1)
				(type default)
			)
			(layer "B.Fab")
		)
		(fp_line
			(start 0.67945 -0.305054)
			(end 0.12065 -0.305054)
			(stroke
				(width 0.1)
				(type default)
			)
			(layer "B.Fab")
		)
		(fp_line
			(start 0.12065 0.3048)
			(end 0.67945 0.3048)
			(stroke
				(width 0.1)
				(type default)
			)
			(layer "B.Fab")
		)
		(fp_line
			(start 0.12065 0.2794)
			(end 0.12065 0.3048)
			(stroke
				(width 0.1)
				(type default)
			)
			(layer "B.Fab")
		)
		(fp_line
			(start 0.12065 -0.2794)
			(end -0.12065 -0.2794)
			(stroke
				(width 0.1)
				(type default)
			)
			(layer "B.Fab")
		)
		(fp_line
			(start 0.12065 -0.305054)
			(end 0.12065 -0.2794)
			(stroke
				(width 0.1)
				(type default)
			)
			(layer "B.Fab")
		)
		(fp_line
			(start -0.120396 0.3048)
			(end -0.120396 0.2794)
			(stroke
				(width 0.1)
				(type default)
			)
			(layer "B.Fab")
		)
		(fp_line
			(start -0.120396 0.2794)
			(end 0.12065 0.2794)
			(stroke
				(width 0.1)
				(type default)
			)
			(layer "B.Fab")
		)
		(fp_line
			(start -0.12065 -0.2794)
			(end -0.12065 -0.3048)
			(stroke
				(width 0.1)
				(type default)
			)
			(layer "B.Fab")
		)
		(fp_line
			(start -0.12065 -0.3048)
			(end -0.67945 -0.3048)
			(stroke
				(width 0.1)
				(type default)
			)
			(layer "B.Fab")
		)
		(fp_line
			(start -0.67945 0.3048)
			(end -0.120396 0.3048)
			(stroke
				(width 0.1)
				(type default)
			)
			(layer "B.Fab")
		)
		(fp_line
			(start -0.67945 -0.3048)
			(end -0.67945 0.3048)
			(stroke
				(width 0.1)
				(type default)
			)
			(layer "B.Fab")
		)
		(pad "1" smd circle
			(at 0.40005 0)
			(size 0 0)
			(layers "B.Cu" "B.Mask" "B.Paste")
			(net "SMB_PDB_MISC_SDA_R")
		)
		(pad "2" smd circle
			(at -0.40005 0)
			(size 0 0)
			(layers "B.Cu" "B.Mask" "B.Paste")
			(net "P3V3_AUX")
		)
	)
	(footprint ""
		(layer "B.Cu")
		(at 235.204 -70.993 90)
		(property "Reference" "R199"
			(at 0 0 90)
			(layer "B.SilkS")
			(hide yes)
			(effects
				(font
					(size 1.27 1.27)
				)
				(justify mirror)
			)
		)
		(property "Value" ""
			(at 0 0 90)
			(layer "B.Fab")
			(effects
				(font
					(size 1.27 1.27)
				)
				(justify mirror)
			)
		)
		(duplicate_pad_numbers_are_jumpers no)
		(fp_line
			(start 0.7874 -0.4064)
			(end -0.7874 -0.4064)
			(stroke
				(width 0.1524)
				(type default)
			)
			(layer "B.SilkS")
		)
		(fp_line
			(start -0.7874 -0.4064)
			(end -0.7874 0.4064)
			(stroke
				(width 0.1524)
				(type default)
			)
			(layer "B.SilkS")
		)
		(fp_line
			(start 0.7874 0.4064)
			(end 0.7874 -0.4064)
			(stroke
				(width 0.1524)
				(type default)
			)
			(layer "B.SilkS")
		)
		(fp_line
			(start -0.7874 0.4064)
			(end 0.7874 0.4064)
			(stroke
				(width 0.1524)
				(type default)
			)
			(layer "B.SilkS")
		)
		(fp_line
			(start 0.67945 -0.305054)
			(end 0.12065 -0.305054)
			(stroke
				(width 0.1)
				(type default)
			)
			(layer "B.Fab")
		)
		(fp_line
			(start 0.12065 -0.305054)
			(end 0.12065 -0.2794)
			(stroke
				(width 0.1)
				(type default)
			)
			(layer "B.Fab")
		)
		(fp_line
			(start -0.12065 -0.3048)
			(end -0.67945 -0.3048)
			(stroke
				(width 0.1)
				(type default)
			)
			(layer "B.Fab")
		)
		(fp_line
			(start -0.67945 -0.3048)
			(end -0.67945 0.3048)
			(stroke
				(width 0.1)
				(type default)
			)
			(layer "B.Fab")
		)
		(fp_line
			(start 0.12065 -0.2794)
			(end -0.12065 -0.2794)
			(stroke
				(width 0.1)
				(type default)
			)
			(layer "B.Fab")
		)
		(fp_line
			(start -0.12065 -0.2794)
			(end -0.12065 -0.3048)
			(stroke
				(width 0.1)
				(type default)
			)
			(layer "B.Fab")
		)
		(fp_line
			(start 0.12065 0.2794)
			(end 0.12065 0.3048)
			(stroke
				(width 0.1)
				(type default)
			)
			(layer "B.Fab")
		)
		(fp_line
			(start -0.120396 0.2794)
			(end 0.12065 0.2794)
			(stroke
				(width 0.1)
				(type default)
			)
			(layer "B.Fab")
		)
		(fp_line
			(start 0.67945 0.3048)
			(end 0.67945 -0.305054)
			(stroke
				(width 0.1)
				(type default)
			)
			(layer "B.Fab")
		)
		(fp_line
			(start 0.12065 0.3048)
			(end 0.67945 0.3048)
			(stroke
				(width 0.1)
				(type default)
			)
			(layer "B.Fab")
		)
		(fp_line
			(start -0.120396 0.3048)
			(end -0.120396 0.2794)
			(stroke
				(width 0.1)
				(type default)
			)
			(layer "B.Fab")
		)
		(fp_line
			(start -0.67945 0.3048)
			(end -0.120396 0.3048)
			(stroke
				(width 0.1)
				(type default)
			)
			(layer "B.Fab")
		)
		(pad "1" smd circle
			(at 0.40005 0 270)
			(size 0 0)
			(layers "B.Cu" "B.Mask" "B.Paste")
			(net "P3V3_AUX")
		)
		(pad "2" smd circle
			(at -0.40005 0 270)
			(size 0 0)
			(layers "B.Cu" "B.Mask" "B.Paste")
			(net "P3V3_AUX_SCALED")
		)
	)
)
